# OAM Pin map rev 1.0.xlsx — Rev History (pin-map)
| Rev | Date | Changes |
| 0.1-0.36 |  | Internal release |
| 0.36 | 43425 | Added pin list for each connector and pin compare sections Removed duplicated and WIP pin maps Swapped P48V and P12V pins Relocated P3V3 and PLVIO from connector 1 to connector 0 Reduced SerDes1 from 20 to 16 lanes Reorder Misc signals across the two connectors Reorder Connector 1 in order to have SerDes Reserved link on upper section and avoid using orphan pairs Reorder connector 0 to improved PCB type 3/4 breakout in 4 layers |
| 0.37 | 43448 | *Added Test 12, TEST13 and TEST14 on connector 1 *Change TEST 10 and TEST 11 from Connector 0 to Connector 1 *Fixed duplicated S1_RX15 and S1_TX14 |
| 0.38 | 2/05/20019 | Connector 0 changes: *Converted RFU pins F53/54 and G55/56 to GND *Updated 12V and 48V pin count and re-order power pins *Renamed RSVD2 to MANF_MODE# *Renamed RSVD3 to FW_RECOVERY# *Renamed RSVD4 to TEST_MODE# *Change PCIE Tx/RX naming to follow Module connectivity POV Connector 1 changes: *Changed QSFP side band signals pins negative logic indication from _N to # *Added MODULE_DEBUG_EN# and DEBUG_PORT_PRST# *Added THERMTRIP#  *Changed RLINK_CAP[1:0] to RFU  *Change STATUS_LED_GREEN, STATUS_LED_RED, STATUS_LED_BLUE to RFU *Added SCALE_DEBUG_EN#   *Added DEBUG_PORT_PRSNT#  *Added MNGMT_LINK0TP/N, MNGMT_LINK0RP/N, MNGMT_LINK1TP/N, MNGMT_LINK1RP/N *Changed SerDes_R Tx/RX naming to follow Module connectivity POV *Changed PLVIO to PVREF |
| 0.8 | 43532 | *Changed AUX_REFCLKP/N pin names to AUX_100M_REFCLKP/N on Connector 1 pins F61, F62 *Added AUX_156M_REFCLKP and AUX_156M_REFCLKN on Connector 1 pins  H45, H46 *Changed pin G55 SCALE_DEBUG_EN# to SCALE_DEBUG_EN |
| 0.81 | 43574 | *Change SerDes pin map. |
| 0.9 | 43576 | *update typos for SerDes4. |
|  | 43578 | *update typos for conn1 pin J40 S5_RX5P to S5_RX4P. |
|  | 43590 | *update typos: Connector_1 pin updated C11 S6_T6N to S6_TX6N                                 Connector_1 pin updated L48 S6_RX9P to S6_RX8P |
| 1 | 43622 | *Swapped  S2 pin polarity to match with S1 and S3 *Changed SerDes R from 20 bits to 16-bits *Added PWRRDT#0 and PWRRDT#1 for power reduction to F25/F26 *Renamed SerDes R to SerDes 7 *Renamed SerDes 6 to SerDes 4 *Renamed SerDes 4 to SerDes 6 |
